(kicad_pcb
	(version 20260206)
	(generator "pcbnew")
	(generator_version "10.0")
	(general
		(thickness 1.6)
		(legacy_teardrops no)
	)
	(paper "A4")
	(title_block
		(title "Wiwynn_Tioga_Pass_MB.brd")
		(comment 1 "Tioga Pass / footprints 4540-4542 of 4770")
	)
	(layers
		(0 "F.Cu" signal "TOP")
		(4 "In1.Cu" signal "L2GND")
		(6 "In2.Cu" signal "L3")
		(8 "In3.Cu" signal "L4GND")
		(10 "In4.Cu" signal "L5")
		(12 "In5.Cu" signal "L6GND")
		(14 "In6.Cu" signal "L7VCC")
		(16 "In7.Cu" signal "L8VCC")
		(18 "In8.Cu" signal "L9GND")
		(20 "In9.Cu" signal "L10")
		(22 "In10.Cu" signal "L11GND")
		(24 "In11.Cu" signal "L12")
		(26 "In12.Cu" signal "L13GND")
		(2 "B.Cu" signal "BOTTOM")
		(9 "F.Adhes" user "F.Adhesive")
		(11 "B.Adhes" user "B.Adhesive")
		(13 "F.Paste" user "Package Geometry/Pastemask Top")
		(15 "B.Paste" user "Package Geometry/Pastemask Bottom")
		(5 "F.SilkS" user "Ref Des/Silkscreen Top")
		(7 "B.SilkS" user "Ref Des/Silkscreen Bottom")
		(1 "F.Mask" user "Board Geometry/Soldermask Top")
		(3 "B.Mask" user "Board Geometry/Soldermask Bottom")
		(17 "Dwgs.User" user "User.Drawings")
		(19 "Cmts.User" user "User.Comments")
		(21 "Eco1.User" user "User.Eco1")
		(23 "Eco2.User" user "User.Eco2")
		(25 "Edge.Cuts" user "Board Geometry/Outline")
		(27 "Margin" user)
		(31 "F.CrtYd" user "Package Geometry/Place Bound Top")
		(29 "B.CrtYd" user "Package Geometry/Place Bound Bottom")
		(35 "F.Fab" user "Ref Des/Assembly Top")
		(33 "B.Fab" user "Ref Des/Assembly Bottom")
	)
	(footprint ""
		(layer "B.Cu")
		(at 314.0964 -31.718758)
		(property "Reference" "WR8D30"
			(at 0.8382 -0.67818 0)
			(unlocked yes)
			(layer "B.SilkS")
			(effects
				(font
					(size 0.4064 0.254)
					(thickness 0.1524)
				)
				(justify left mirror)
			)
		)
		(property "Value" ""
			(at 0 0 0)
			(layer "B.Fab")
			(effects
				(font
					(size 1.27 1.27)
				)
				(justify mirror)
			)
		)
		(duplicate_pad_numbers_are_jumpers no)
		(fp_poly
			(pts
				(xy 0.2794 -0.1016) (xy -0.2794 -0.1016) (xy -0.2794 0.9906) (xy 0.2794 0.9906)
			)
			(stroke
				(width 0)
				(type default)
			)
			(fill no)
			(layer "B.CrtYd")
		)
		(fp_line
			(start -0.2794 -0.1016)
			(end 0.2794 -0.1016)
			(stroke
				(width 0.1)
				(type default)
			)
			(layer "B.Fab")
		)
		(fp_line
			(start -0.2794 0.9906)
			(end -0.2794 -0.1016)
			(stroke
				(width 0.1)
				(type default)
			)
			(layer "B.Fab")
		)
		(fp_line
			(start 0.2794 -0.1016)
			(end 0.2794 0.9906)
			(stroke
				(width 0.1)
				(type default)
			)
			(layer "B.Fab")
		)
		(fp_line
			(start 0.2794 0.9906)
			(end -0.2794 0.9906)
			(stroke
				(width 0.1)
				(type default)
			)
			(layer "B.Fab")
		)
		(pad "1" smd rect
			(at 0 0 180)
			(size 0.508 0.508)
			(layers "B.Cu" "B.Mask" "B.Paste")
			(net "FM_ADR_COMPLETE_CPU1_N")
		)
		(pad "2" smd rect
			(at 0 0.889 180)
			(size 0.508 0.508)
			(layers "B.Cu" "B.Mask" "B.Paste")
			(net "IRQ_DIMM_SAVE_CPU1_R_N")
		)
		(zone
			(layer "B.Cu")
			(hatch none 0.5)
			(connect_pads
				(clearance 0)
			)
			(min_thickness 0.25)
			(keepout
				(tracks allowed)
				(vias not_allowed)
				(pads allowed)
				(copperpour not_allowed)
				(footprints allowed)
			)
			(placement
				(enabled no)
				(sheetname "")
			)
			(fill
				(thermal_gap 0.5)
				(thermal_bridge_width 0.5)
				(island_removal_mode 0)
			)
			(polygon
				(pts
					(xy 314.3504 -31.464758) (xy 313.8424 -31.464758) (xy 313.8424 -31.083758) (xy 314.3504 -31.083758)
				)
			)
		)
		(zone
			(layer "B.Cu")
			(hatch none 0.5)
			(connect_pads
				(clearance 0)
			)
			(min_thickness 0.25)
			(keepout
				(tracks not_allowed)
				(vias allowed)
				(pads allowed)
				(copperpour not_allowed)
				(footprints allowed)
			)
			(placement
				(enabled no)
				(sheetname "")
			)
			(fill
				(thermal_gap 0.5)
				(thermal_bridge_width 0.5)
				(island_removal_mode 0)
			)
			(polygon
				(pts
					(xy 314.3504 -31.083758) (xy 313.8424 -31.083758) (xy 313.8424 -31.464758) (xy 314.3504 -31.464758)
				)
			)
		)
	)
	(footprint ""
		(layer "B.Cu")
		(at 396.875 -87.3252 180)
		(property "Reference" "R8W7"
			(at 0.8382 -0.67818 180)
			(unlocked yes)
			(layer "B.SilkS")
			(effects
				(font
					(size 0.4064 0.254)
					(thickness 0.1524)
				)
				(justify left mirror)
			)
		)
		(property "Value" ""
			(at 0 0 0)
			(layer "B.Fab")
			(effects
				(font
					(size 1.27 1.27)
				)
				(justify mirror)
			)
		)
		(duplicate_pad_numbers_are_jumpers no)
		(fp_poly
			(pts
				(xy 0.2794 -0.1016) (xy -0.2794 -0.1016) (xy -0.2794 0.9906) (xy 0.2794 0.9906)
			)
			(stroke
				(width 0)
				(type default)
			)
			(fill no)
			(layer "B.CrtYd")
		)
		(fp_line
			(start 0.2794 0.9906)
			(end -0.2794 0.9906)
			(stroke
				(width 0.1)
				(type default)
			)
			(layer "B.Fab")
		)
		(fp_line
			(start 0.2794 -0.1016)
			(end 0.2794 0.9906)
			(stroke
				(width 0.1)
				(type default)
			)
			(layer "B.Fab")
		)
		(fp_line
			(start -0.2794 0.9906)
			(end -0.2794 -0.1016)
			(stroke
				(width 0.1)
				(type default)
			)
			(layer "B.Fab")
		)
		(fp_line
			(start -0.2794 -0.1016)
			(end 0.2794 -0.1016)
			(stroke
				(width 0.1)
				(type default)
			)
			(layer "B.Fab")
		)
		(pad "1" smd rect
			(at 0 0)
			(size 0.508 0.508)
			(layers "B.Cu" "B.Mask" "B.Paste")
			(net "P3V3_STBY")
		)
		(pad "2" smd rect
			(at 0 0.889)
			(size 0.508 0.508)
			(layers "B.Cu" "B.Mask" "B.Paste")
			(net "SMB_VR_STBY_LVC3_SCL_R1")
		)
		(zone
			(layer "B.Cu")
			(hatch none 0.5)
			(connect_pads
				(clearance 0)
			)
			(min_thickness 0.25)
			(keepout
				(tracks not_allowed)
				(vias allowed)
				(pads allowed)
				(copperpour not_allowed)
				(footprints allowed)
			)
			(placement
				(enabled no)
				(sheetname "")
			)
			(fill
				(thermal_gap 0.5)
				(thermal_bridge_width 0.5)
				(island_removal_mode 0)
			)
			(polygon
				(pts
					(xy 396.621 -87.9602) (xy 397.129 -87.9602) (xy 397.129 -87.5792) (xy 396.621 -87.5792)
				)
			)
		)
		(zone
			(layer "B.Cu")
			(hatch none 0.5)
			(connect_pads
				(clearance 0)
			)
			(min_thickness 0.25)
			(keepout
				(tracks allowed)
				(vias not_allowed)
				(pads allowed)
				(copperpour not_allowed)
				(footprints allowed)
			)
			(placement
				(enabled no)
				(sheetname "")
			)
			(fill
				(thermal_gap 0.5)
				(thermal_bridge_width 0.5)
				(island_removal_mode 0)
			)
			(polygon
				(pts
					(xy 396.621 -87.5792) (xy 397.129 -87.5792) (xy 397.129 -87.9602) (xy 396.621 -87.9602)
				)
			)
		)
	)
	(footprint ""
		(layer "B.Cu")
		(at 447.928238 -52.407058)
		(property "Reference" "C2R13"
			(at 0 0 0)
			(layer "B.SilkS")
			(hide yes)
			(effects
				(font
					(size 1.27 1.27)
				)
				(justify mirror)
			)
		)
		(property "Value" ""
			(at 0 0 0)
			(layer "B.Fab")
			(effects
				(font
					(size 1.27 1.27)
				)
				(justify mirror)
			)
		)
		(duplicate_pad_numbers_are_jumpers no)
		(fp_poly
			(pts
				(xy -0.3048 -0.1016) (xy -0.3048 0.9906) (xy 0.3048 0.9906) (xy 0.3048 -0.1016)
			)
			(stroke
				(width 0)
				(type default)
			)
			(fill no)
			(layer "B.CrtYd")
		)
		(fp_line
			(start -0.3048 -0.1016)
			(end 0.3048 -0.1016)
			(stroke
				(width 0.1)
				(type default)
			)
			(layer "B.Fab")
		)
		(fp_line
			(start -0.3048 0.9906)
			(end -0.3048 -0.1016)
			(stroke
				(width 0.1)
				(type default)
			)
			(layer "B.Fab")
		)
		(fp_line
			(start 0.3048 -0.1016)
			(end 0.3048 0.9906)
			(stroke
				(width 0.1)
				(type default)
			)
			(layer "B.Fab")
		)
		(fp_line
			(start 0.3048 0.9906)
			(end -0.3048 0.9906)
			(stroke
				(width 0.1)
				(type default)
			)
			(layer "B.Fab")
		)
		(pad "1" smd rect
			(at 0 0 180)
			(size 0.508 0.508)
			(layers "B.Cu" "B.Mask" "B.Paste")
			(net "P3E_CPU0_PE3_OCP_TXN<5>")
		)
		(pad "2" smd rect
			(at 0 0.889 180)
			(size 0.508 0.508)
			(layers "B.Cu" "B.Mask" "B.Paste")
			(net "P3E_OCP_CPU0_PE3_C_TXN<5>")
		)
		(zone
			(layer "B.Cu")
			(hatch none 0.5)
			(connect_pads
				(clearance 0)
			)
			(min_thickness 0.25)
			(keepout
				(tracks allowed)
				(vias not_allowed)
				(pads allowed)
				(copperpour not_allowed)
				(footprints allowed)
			)
			(placement
				(enabled no)
				(sheetname "")
			)
			(fill
				(thermal_gap 0.5)
				(thermal_bridge_width 0.5)
				(island_removal_mode 0)
			)
			(polygon
				(pts
					(xy 448.182238 -52.153058) (xy 447.674238 -52.153058) (xy 447.674238 -51.772058) (xy 448.182238 -51.772058)
				)
			)
		)
		(zone
			(layer "B.Cu")
			(hatch none 0.5)
			(connect_pads
				(clearance 0)
			)
			(min_thickness 0.25)
			(keepout
				(tracks not_allowed)
				(vias allowed)
				(pads allowed)
				(copperpour not_allowed)
				(footprints allowed)
			)
			(placement
				(enabled no)
				(sheetname "")
			)
			(fill
				(thermal_gap 0.5)
				(thermal_bridge_width 0.5)
				(island_removal_mode 0)
			)
			(polygon
				(pts
					(xy 448.182238 -51.772058) (xy 447.674238 -51.772058) (xy 447.674238 -52.153058) (xy 448.182238 -52.153058)
				)
			)
		)
	)
)
